(kicad_pcb
	(version 20260206)
	(generator "pcbnew")
	(generator_version "10.0")
	(general
		(thickness 1.6)
		(legacy_teardrops no)
	)
	(paper "A4")
	(title_block
		(title "03242023_DA0F0TMBIJ0_F0T_Motherboard_J_brd_V01_OCP.brd")
		(comment 1 "Grand Teton / footprint 3431 of 6105 (J28), pads 113-224 of 291")
	)
	(layers
		(0 "F.Cu" signal "TOP")
		(4 "In1.Cu" signal "GND")
		(6 "In2.Cu" signal "IN1")
		(8 "In3.Cu" signal "GND1")
		(10 "In4.Cu" signal "IN2")
		(12 "In5.Cu" signal "GND2")
		(14 "In6.Cu" signal "IN3")
		(16 "In7.Cu" signal "GND3")
		(18 "In8.Cu" signal "VCC")
		(20 "In9.Cu" signal "VCC1")
		(22 "In10.Cu" signal "GND4")
		(24 "In11.Cu" signal "IN4")
		(26 "In12.Cu" signal "GND5")
		(28 "In13.Cu" signal "IN5")
		(30 "In14.Cu" signal "GND6")
		(32 "In15.Cu" signal "IN6")
		(34 "In16.Cu" signal "GND7")
		(2 "B.Cu" signal "BOTTOM")
		(9 "F.Adhes" user "F.Adhesive")
		(11 "B.Adhes" user "B.Adhesive")
		(13 "F.Paste" user "Package Geometry/Pastemask Top")
		(15 "B.Paste" user "Package Geometry/Pastemask Bottom")
		(5 "F.SilkS" user "Ref Des/Silkscreen Top")
		(7 "B.SilkS" user "Ref Des/Silkscreen Bottom")
		(1 "F.Mask" user "Board Geometry/Soldermask Top")
		(3 "B.Mask" user "Board Geometry/Soldermask Bottom")
		(17 "Dwgs.User" user "User.Drawings")
		(19 "Cmts.User" user "User.Comments")
		(21 "Eco1.User" user "User.Eco1")
		(23 "Eco2.User" user "User.Eco2")
		(25 "Edge.Cuts" user "Board Geometry/Outline")
		(27 "Margin" user)
		(31 "F.CrtYd" user "Package Geometry/Place Bound Top")
		(29 "B.CrtYd" user "Package Geometry/Place Bound Bottom")
		(35 "F.Fab" user "Ref Des/Assembly Top")
		(33 "B.Fab" user "Ref Des/Assembly Bottom")
	)
	(footprint ""
		(layer "F.Cu")
		(at 175.95088 -258.091686)
		(property "Reference" "J28"
			(at -0.26924 -81.680812 0)
			(unlocked yes)
			(layer "F.SilkS")
			(effects
				(font
					(size 0.7874 0.5842)
					(thickness 0.1524)
				)
				(justify left)
			)
		)
		(property "Value" ""
			(at 0 0 0)
			(layer "F.Fab")
			(effects
				(font
					(size 1.27 1.27)
				)
			)
		)
		(duplicate_pad_numbers_are_jumpers no)
		(pad "113" smd rect
			(at -2.050034 36.975034 270)
			(size 0.519938 1.4986)
			(layers "F.Cu" "F.Mask" "F.Paste")
			(net "M_F_CPU1_SB_DQ<9>")
		)
		(pad "114" smd rect
			(at -2.050034 37.824918 270)
			(size 0.519938 1.4986)
			(layers "F.Cu" "F.Mask" "F.Paste")
			(net "GND")
		)
		(pad "115" smd rect
			(at -2.050034 38.675056 270)
			(size 0.519938 1.4986)
			(layers "F.Cu" "F.Mask" "F.Paste")
			(net "M_F_CPU1_SB_DQS_DP<1>")
		)
		(pad "116" smd rect
			(at -2.050034 39.52494 270)
			(size 0.519938 1.4986)
			(layers "F.Cu" "F.Mask" "F.Paste")
			(net "M_F_CPU1_SB_DQS_DN<1>")
		)
		(pad "117" smd rect
			(at -2.050034 40.375078 270)
			(size 0.519938 1.4986)
			(layers "F.Cu" "F.Mask" "F.Paste")
			(net "GND")
		)
		(pad "118" smd rect
			(at -2.050034 41.224962 270)
			(size 0.519938 1.4986)
			(layers "F.Cu" "F.Mask" "F.Paste")
			(net "M_F_CPU1_SB_DQ<12>")
		)
		(pad "119" smd rect
			(at -2.050034 42.0751 270)
			(size 0.519938 1.4986)
			(layers "F.Cu" "F.Mask" "F.Paste")
			(net "GND")
		)
		(pad "120" smd rect
			(at -2.050034 42.924984 270)
			(size 0.519938 1.4986)
			(layers "F.Cu" "F.Mask" "F.Paste")
			(net "M_F_CPU1_SB_DQ<13>")
		)
		(pad "121" smd rect
			(at -2.050034 43.775122 270)
			(size 0.519938 1.4986)
			(layers "F.Cu" "F.Mask" "F.Paste")
			(net "GND")
		)
		(pad "122" smd rect
			(at -2.050034 44.625006 270)
			(size 0.519938 1.4986)
			(layers "F.Cu" "F.Mask" "F.Paste")
			(net "M_F_CPU1_SB_DQ<16>")
		)
		(pad "123" smd rect
			(at -2.050034 45.47489 270)
			(size 0.519938 1.4986)
			(layers "F.Cu" "F.Mask" "F.Paste")
			(net "GND")
		)
		(pad "124" smd rect
			(at -2.050034 46.325028 270)
			(size 0.519938 1.4986)
			(layers "F.Cu" "F.Mask" "F.Paste")
			(net "M_F_CPU1_SB_DQ<17>")
		)
		(pad "125" smd rect
			(at -2.050034 47.174912 270)
			(size 0.519938 1.4986)
			(layers "F.Cu" "F.Mask" "F.Paste")
			(net "GND")
		)
		(pad "126" smd rect
			(at -2.050034 48.02505 270)
			(size 0.519938 1.4986)
			(layers "F.Cu" "F.Mask" "F.Paste")
			(net "M_F_CPU1_SB_DQS_DP<2>")
		)
		(pad "127" smd rect
			(at -2.050034 48.874934 270)
			(size 0.519938 1.4986)
			(layers "F.Cu" "F.Mask" "F.Paste")
			(net "M_F_CPU1_SB_DQS_DN<2>")
		)
		(pad "128" smd rect
			(at -2.050034 49.725072 270)
			(size 0.519938 1.4986)
			(layers "F.Cu" "F.Mask" "F.Paste")
			(net "GND")
		)
		(pad "129" smd rect
			(at -2.050034 50.574956 270)
			(size 0.519938 1.4986)
			(layers "F.Cu" "F.Mask" "F.Paste")
			(net "M_F_CPU1_SB_DQ<20>")
		)
		(pad "130" smd rect
			(at -2.050034 51.425094 270)
			(size 0.519938 1.4986)
			(layers "F.Cu" "F.Mask" "F.Paste")
			(net "GND")
		)
		(pad "131" smd rect
			(at -2.050034 52.274978 270)
			(size 0.519938 1.4986)
			(layers "F.Cu" "F.Mask" "F.Paste")
			(net "M_F_CPU1_SB_DQ<21>")
		)
		(pad "132" smd rect
			(at -2.050034 53.125116 270)
			(size 0.519938 1.4986)
			(layers "F.Cu" "F.Mask" "F.Paste")
			(net "GND")
		)
		(pad "133" smd rect
			(at -2.050034 53.975 270)
			(size 0.519938 1.4986)
			(layers "F.Cu" "F.Mask" "F.Paste")
			(net "M_F_CPU1_SB_DQ<24>")
		)
		(pad "134" smd rect
			(at -2.050034 54.824884 270)
			(size 0.519938 1.4986)
			(layers "F.Cu" "F.Mask" "F.Paste")
			(net "GND")
		)
		(pad "135" smd rect
			(at -2.050034 55.675022 270)
			(size 0.519938 1.4986)
			(layers "F.Cu" "F.Mask" "F.Paste")
			(net "M_F_CPU1_SB_DQ<25>")
		)
		(pad "136" smd rect
			(at -2.050034 56.524906 270)
			(size 0.519938 1.4986)
			(layers "F.Cu" "F.Mask" "F.Paste")
			(net "GND")
		)
		(pad "137" smd rect
			(at -2.050034 57.375044 270)
			(size 0.519938 1.4986)
			(layers "F.Cu" "F.Mask" "F.Paste")
			(net "M_F_CPU1_SB_DQS_DP<3>")
		)
		(pad "138" smd rect
			(at -2.050034 58.224928 270)
			(size 0.519938 1.4986)
			(layers "F.Cu" "F.Mask" "F.Paste")
			(net "M_F_CPU1_SB_DQS_DN<3>")
		)
		(pad "139" smd rect
			(at -2.050034 59.075066 270)
			(size 0.519938 1.4986)
			(layers "F.Cu" "F.Mask" "F.Paste")
			(net "GND")
		)
		(pad "140" smd rect
			(at -2.050034 59.92495 270)
			(size 0.519938 1.4986)
			(layers "F.Cu" "F.Mask" "F.Paste")
			(net "M_F_CPU1_SB_DQ<28>")
		)
		(pad "141" smd rect
			(at -2.050034 60.775088 270)
			(size 0.519938 1.4986)
			(layers "F.Cu" "F.Mask" "F.Paste")
			(net "GND")
		)
		(pad "142" smd rect
			(at -2.050034 61.624972 270)
			(size 0.519938 1.4986)
			(layers "F.Cu" "F.Mask" "F.Paste")
			(net "M_F_CPU1_SB_DQ<29>")
		)
		(pad "143" smd rect
			(at -2.050034 62.47511 270)
			(size 0.519938 1.4986)
			(layers "F.Cu" "F.Mask" "F.Paste")
			(net "GND")
		)
		(pad "144" smd rect
			(at -2.050034 63.324994 270)
			(size 0.519938 1.4986)
			(layers "F.Cu" "F.Mask" "F.Paste")
			(net "TP_CHF_CPU1_DIMM2_FRU_1")
		)
		(pad "145" smd rect
			(at 2.050034 -63.324994 270)
			(size 0.519938 1.4986)
			(layers "F.Cu" "F.Mask" "F.Paste")
			(net "P12V_S3_AUX_CPU1_NVDIMM")
		)
		(pad "146" smd rect
			(at 2.050034 -62.47511 270)
			(size 0.519938 1.4986)
			(layers "F.Cu" "F.Mask" "F.Paste")
			(net "P12V_S3_AUX_CPU1_NVDIMM")
		)
		(pad "147" smd rect
			(at 2.050034 -61.624972 270)
			(size 0.519938 1.4986)
			(layers "F.Cu" "F.Mask" "F.Paste")
			(net "PWRGD_CHF_CPU1_DIMM2")
		)
		(pad "148" smd rect
			(at 2.050034 -60.775088 270)
			(size 0.519938 1.4986)
			(layers "F.Cu" "F.Mask" "F.Paste")
			(net "PD_CHF_CPU1_DIMM2_SAA")
		)
		(pad "149" smd rect
			(at 2.050034 -59.92495 270)
			(size 0.519938 1.4986)
			(layers "F.Cu" "F.Mask" "F.Paste")
			(net "TP_CHF_CPU1_DIMM2_FRU_2")
		)
		(pad "150" smd rect
			(at 2.050034 -59.075066 270)
			(size 0.519938 1.4986)
			(layers "F.Cu" "F.Mask" "F.Paste")
			(net "TP_CHF_CPU1_DIMM2_FRU_3")
		)
		(pad "151" smd rect
			(at 2.050034 -58.224928 270)
			(size 0.519938 1.4986)
			(layers "F.Cu" "F.Mask" "F.Paste")
			(net "GND")
		)
		(pad "152" smd rect
			(at 2.050034 -57.375044 270)
			(size 0.519938 1.4986)
			(layers "F.Cu" "F.Mask" "F.Paste")
			(net "M_F_CPU1_SA_DQ<2>")
		)
		(pad "153" smd rect
			(at 2.050034 -56.524906 270)
			(size 0.519938 1.4986)
			(layers "F.Cu" "F.Mask" "F.Paste")
			(net "GND")
		)
		(pad "154" smd rect
			(at 2.050034 -55.675022 270)
			(size 0.519938 1.4986)
			(layers "F.Cu" "F.Mask" "F.Paste")
			(net "M_F_CPU1_SA_DQ<3>")
		)
		(pad "155" smd rect
			(at 2.050034 -54.824884 270)
			(size 0.519938 1.4986)
			(layers "F.Cu" "F.Mask" "F.Paste")
			(net "GND")
		)
		(pad "156" smd rect
			(at 2.050034 -53.975 270)
			(size 0.519938 1.4986)
			(layers "F.Cu" "F.Mask" "F.Paste")
			(net "M_F_CPU1_SA_DQS_DN<5>")
		)
		(pad "157" smd rect
			(at 2.050034 -53.125116 270)
			(size 0.519938 1.4986)
			(layers "F.Cu" "F.Mask" "F.Paste")
			(net "M_F_CPU1_SA_DQS_DP<5>")
		)
		(pad "158" smd rect
			(at 2.050034 -52.274978 270)
			(size 0.519938 1.4986)
			(layers "F.Cu" "F.Mask" "F.Paste")
			(net "GND")
		)
		(pad "159" smd rect
			(at 2.050034 -51.425094 270)
			(size 0.519938 1.4986)
			(layers "F.Cu" "F.Mask" "F.Paste")
			(net "M_F_CPU1_SA_DQ<6>")
		)
		(pad "160" smd rect
			(at 2.050034 -50.574956 270)
			(size 0.519938 1.4986)
			(layers "F.Cu" "F.Mask" "F.Paste")
			(net "GND")
		)
		(pad "161" smd rect
			(at 2.050034 -49.725072 270)
			(size 0.519938 1.4986)
			(layers "F.Cu" "F.Mask" "F.Paste")
			(net "M_F_CPU1_SA_DQ<7>")
		)
		(pad "162" smd rect
			(at 2.050034 -48.874934 270)
			(size 0.519938 1.4986)
			(layers "F.Cu" "F.Mask" "F.Paste")
			(net "GND")
		)
		(pad "163" smd rect
			(at 2.050034 -48.02505 270)
			(size 0.519938 1.4986)
			(layers "F.Cu" "F.Mask" "F.Paste")
			(net "M_F_CPU1_SA_DQ<10>")
		)
		(pad "164" smd rect
			(at 2.050034 -47.174912 270)
			(size 0.519938 1.4986)
			(layers "F.Cu" "F.Mask" "F.Paste")
			(net "GND")
		)
		(pad "165" smd rect
			(at 2.050034 -46.325028 270)
			(size 0.519938 1.4986)
			(layers "F.Cu" "F.Mask" "F.Paste")
			(net "M_F_CPU1_SA_DQ<11>")
		)
		(pad "166" smd rect
			(at 2.050034 -45.47489 270)
			(size 0.519938 1.4986)
			(layers "F.Cu" "F.Mask" "F.Paste")
			(net "GND")
		)
		(pad "167" smd rect
			(at 2.050034 -44.625006 270)
			(size 0.519938 1.4986)
			(layers "F.Cu" "F.Mask" "F.Paste")
			(net "M_F_CPU1_SA_DQS_DN<6>")
		)
		(pad "168" smd rect
			(at 2.050034 -43.775122 270)
			(size 0.519938 1.4986)
			(layers "F.Cu" "F.Mask" "F.Paste")
			(net "M_F_CPU1_SA_DQS_DP<6>")
		)
		(pad "169" smd rect
			(at 2.050034 -42.924984 270)
			(size 0.519938 1.4986)
			(layers "F.Cu" "F.Mask" "F.Paste")
			(net "GND")
		)
		(pad "170" smd rect
			(at 2.050034 -42.0751 270)
			(size 0.519938 1.4986)
			(layers "F.Cu" "F.Mask" "F.Paste")
			(net "M_F_CPU1_SA_DQ<14>")
		)
		(pad "171" smd rect
			(at 2.050034 -41.224962 270)
			(size 0.519938 1.4986)
			(layers "F.Cu" "F.Mask" "F.Paste")
			(net "GND")
		)
		(pad "172" smd rect
			(at 2.050034 -40.375078 270)
			(size 0.519938 1.4986)
			(layers "F.Cu" "F.Mask" "F.Paste")
			(net "M_F_CPU1_SA_DQ<15>")
		)
		(pad "173" smd rect
			(at 2.050034 -39.52494 270)
			(size 0.519938 1.4986)
			(layers "F.Cu" "F.Mask" "F.Paste")
			(net "GND")
		)
		(pad "174" smd rect
			(at 2.050034 -38.675056 270)
			(size 0.519938 1.4986)
			(layers "F.Cu" "F.Mask" "F.Paste")
			(net "M_F_CPU1_SA_DQ<18>")
		)
		(pad "175" smd rect
			(at 2.050034 -37.824918 270)
			(size 0.519938 1.4986)
			(layers "F.Cu" "F.Mask" "F.Paste")
			(net "GND")
		)
		(pad "176" smd rect
			(at 2.050034 -36.975034 270)
			(size 0.519938 1.4986)
			(layers "F.Cu" "F.Mask" "F.Paste")
			(net "M_F_CPU1_SA_DQ<19>")
		)
		(pad "177" smd rect
			(at 2.050034 -36.124896 270)
			(size 0.519938 1.4986)
			(layers "F.Cu" "F.Mask" "F.Paste")
			(net "GND")
		)
		(pad "178" smd rect
			(at 2.050034 -35.275012 270)
			(size 0.519938 1.4986)
			(layers "F.Cu" "F.Mask" "F.Paste")
			(net "M_F_CPU1_SA_DQS_DN<7>")
		)
		(pad "179" smd rect
			(at 2.050034 -34.425128 270)
			(size 0.519938 1.4986)
			(layers "F.Cu" "F.Mask" "F.Paste")
			(net "M_F_CPU1_SA_DQS_DP<7>")
		)
		(pad "180" smd rect
			(at 2.050034 -33.57499 270)
			(size 0.519938 1.4986)
			(layers "F.Cu" "F.Mask" "F.Paste")
			(net "GND")
		)
		(pad "181" smd rect
			(at 2.050034 -32.725106 270)
			(size 0.519938 1.4986)
			(layers "F.Cu" "F.Mask" "F.Paste")
			(net "M_F_CPU1_SA_DQ<22>")
		)
		(pad "182" smd rect
			(at 2.050034 -31.874968 270)
			(size 0.519938 1.4986)
			(layers "F.Cu" "F.Mask" "F.Paste")
			(net "GND")
		)
		(pad "183" smd rect
			(at 2.050034 -31.025084 270)
			(size 0.519938 1.4986)
			(layers "F.Cu" "F.Mask" "F.Paste")
			(net "M_F_CPU1_SA_DQ<23>")
		)
		(pad "184" smd rect
			(at 2.050034 -30.174946 270)
			(size 0.519938 1.4986)
			(layers "F.Cu" "F.Mask" "F.Paste")
			(net "GND")
		)
		(pad "185" smd rect
			(at 2.050034 -29.325062 270)
			(size 0.519938 1.4986)
			(layers "F.Cu" "F.Mask" "F.Paste")
			(net "M_F_CPU1_SA_DQ<26>")
		)
		(pad "186" smd rect
			(at 2.050034 -28.474924 270)
			(size 0.519938 1.4986)
			(layers "F.Cu" "F.Mask" "F.Paste")
			(net "GND")
		)
		(pad "187" smd rect
			(at 2.050034 -27.62504 270)
			(size 0.519938 1.4986)
			(layers "F.Cu" "F.Mask" "F.Paste")
			(net "M_F_CPU1_SA_DQ<27>")
		)
		(pad "188" smd rect
			(at 2.050034 -26.774902 270)
			(size 0.519938 1.4986)
			(layers "F.Cu" "F.Mask" "F.Paste")
			(net "GND")
		)
		(pad "189" smd rect
			(at 2.050034 -25.925018 270)
			(size 0.519938 1.4986)
			(layers "F.Cu" "F.Mask" "F.Paste")
			(net "M_F_CPU1_SA_DQS_DN<8>")
		)
		(pad "190" smd rect
			(at 2.050034 -25.07488 270)
			(size 0.519938 1.4986)
			(layers "F.Cu" "F.Mask" "F.Paste")
			(net "M_F_CPU1_SA_DQS_DP<8>")
		)
		(pad "191" smd rect
			(at 2.050034 -24.224996 270)
			(size 0.519938 1.4986)
			(layers "F.Cu" "F.Mask" "F.Paste")
			(net "GND")
		)
		(pad "192" smd rect
			(at 2.050034 -23.375112 270)
			(size 0.519938 1.4986)
			(layers "F.Cu" "F.Mask" "F.Paste")
			(net "M_F_CPU1_SA_DQ<30>")
		)
		(pad "193" smd rect
			(at 2.050034 -22.524974 270)
			(size 0.519938 1.4986)
			(layers "F.Cu" "F.Mask" "F.Paste")
			(net "GND")
		)
		(pad "194" smd rect
			(at 2.050034 -21.67509 270)
			(size 0.519938 1.4986)
			(layers "F.Cu" "F.Mask" "F.Paste")
			(net "M_F_CPU1_SA_DQ<31>")
		)
		(pad "195" smd rect
			(at 2.050034 -20.824952 270)
			(size 0.519938 1.4986)
			(layers "F.Cu" "F.Mask" "F.Paste")
			(net "GND")
		)
		(pad "196" smd rect
			(at 2.050034 -19.975068 270)
			(size 0.519938 1.4986)
			(layers "F.Cu" "F.Mask" "F.Paste")
			(net "M_F_CPU1_SA_CB<2>")
		)
		(pad "197" smd rect
			(at 2.050034 -19.12493 270)
			(size 0.519938 1.4986)
			(layers "F.Cu" "F.Mask" "F.Paste")
			(net "GND")
		)
		(pad "198" smd rect
			(at 2.050034 -18.275046 270)
			(size 0.519938 1.4986)
			(layers "F.Cu" "F.Mask" "F.Paste")
			(net "M_F_CPU1_SA_CB<3>")
		)
		(pad "199" smd rect
			(at 2.050034 -17.424908 270)
			(size 0.519938 1.4986)
			(layers "F.Cu" "F.Mask" "F.Paste")
			(net "GND")
		)
		(pad "200" smd rect
			(at 2.050034 -16.575024 270)
			(size 0.519938 1.4986)
			(layers "F.Cu" "F.Mask" "F.Paste")
			(net "M_F_CPU1_SA_DQS_DN<9>")
		)
		(pad "201" smd rect
			(at 2.050034 -15.724886 270)
			(size 0.519938 1.4986)
			(layers "F.Cu" "F.Mask" "F.Paste")
			(net "M_F_CPU1_SA_DQS_DP<9>")
		)
		(pad "202" smd rect
			(at 2.050034 -14.875002 270)
			(size 0.519938 1.4986)
			(layers "F.Cu" "F.Mask" "F.Paste")
			(net "GND")
		)
		(pad "203" smd rect
			(at 2.050034 -14.025118 270)
			(size 0.519938 1.4986)
			(layers "F.Cu" "F.Mask" "F.Paste")
			(net "M_F_CPU1_SA_CB<6>")
		)
		(pad "204" smd rect
			(at 2.050034 -13.17498 270)
			(size 0.519938 1.4986)
			(layers "F.Cu" "F.Mask" "F.Paste")
			(net "GND")
		)
		(pad "205" smd rect
			(at 2.050034 -12.325096 270)
			(size 0.519938 1.4986)
			(layers "F.Cu" "F.Mask" "F.Paste")
			(net "M_F_CPU1_SA_CB<7>")
		)
		(pad "206" smd rect
			(at 2.050034 -11.474958 270)
			(size 0.519938 1.4986)
			(layers "F.Cu" "F.Mask" "F.Paste")
			(net "GND")
		)
		(pad "207" smd rect
			(at 2.050034 -10.625074 270)
			(size 0.519938 1.4986)
			(layers "F.Cu" "F.Mask" "F.Paste")
			(net "RST_M_EF_CPU1_FPGA_N")
		)
		(pad "208" smd rect
			(at 2.050034 -9.774936 270)
			(size 0.519938 1.4986)
			(layers "F.Cu" "F.Mask" "F.Paste")
			(net "GND")
		)
		(pad "209" smd rect
			(at 2.050034 -8.925052 270)
			(size 0.519938 1.4986)
			(layers "F.Cu" "F.Mask" "F.Paste")
			(net "M_F_CPU1_SA_CS_N<3>")
		)
		(pad "210" smd rect
			(at 2.050034 -8.074914 270)
			(size 0.519938 1.4986)
			(layers "F.Cu" "F.Mask" "F.Paste")
			(net "GND")
		)
		(pad "211" smd rect
			(at 2.050034 -7.22503 270)
			(size 0.519938 1.4986)
			(layers "F.Cu" "F.Mask" "F.Paste")
			(net "M_F_CPU1_SA_CA<1>")
		)
		(pad "212" smd rect
			(at 2.050034 -6.374892 270)
			(size 0.519938 1.4986)
			(layers "F.Cu" "F.Mask" "F.Paste")
			(net "GND")
		)
		(pad "213" smd rect
			(at 2.050034 -5.525008 270)
			(size 0.519938 1.4986)
			(layers "F.Cu" "F.Mask" "F.Paste")
			(net "M_F_CPU1_SA_CA<3>")
		)
		(pad "214" smd rect
			(at 2.050034 -4.675124 270)
			(size 0.519938 1.4986)
			(layers "F.Cu" "F.Mask" "F.Paste")
			(net "GND")
		)
		(pad "215" smd rect
			(at 2.050034 -3.824986 270)
			(size 0.519938 1.4986)
			(layers "F.Cu" "F.Mask" "F.Paste")
			(net "M_F_CPU1_SA_CA<5>")
		)
		(pad "216" smd rect
			(at 2.050034 -2.975102 270)
			(size 0.519938 1.4986)
			(layers "F.Cu" "F.Mask" "F.Paste")
			(net "GND")
		)
		(pad "217" smd rect
			(at 2.050034 -2.124964 270)
			(size 0.519938 1.4986)
			(layers "F.Cu" "F.Mask" "F.Paste")
			(net "M_F_CPU1_CLK_DP<1>")
		)
		(pad "218" smd rect
			(at 2.050034 -1.27508 270)
			(size 0.519938 1.4986)
			(layers "F.Cu" "F.Mask" "F.Paste")
			(net "M_F_CPU1_CLK_DN<1>")
		)
		(pad "219" smd rect
			(at 2.050034 -0.424942 270)
			(size 0.519938 1.4986)
			(layers "F.Cu" "F.Mask" "F.Paste")
			(net "GND")
		)
		(pad "220" smd rect
			(at 2.050034 5.525008 270)
			(size 0.519938 1.4986)
			(layers "F.Cu" "F.Mask" "F.Paste")
			(net "TP_CHF_CPU1_DIMM2_FRU_4")
		)
		(pad "221" smd rect
			(at 2.050034 6.374892 270)
			(size 0.519938 1.4986)
			(layers "F.Cu" "F.Mask" "F.Paste")
			(net "M_F_CPU1_SB_CA<1>")
		)
		(pad "222" smd rect
			(at 2.050034 7.22503 270)
			(size 0.519938 1.4986)
			(layers "F.Cu" "F.Mask" "F.Paste")
			(net "GND")
		)
		(pad "223" smd rect
			(at 2.050034 8.074914 270)
			(size 0.519938 1.4986)
			(layers "F.Cu" "F.Mask" "F.Paste")
			(net "M_F_CPU1_SB_CA<3>")
		)
		(pad "224" smd rect
			(at 2.050034 8.925052 270)
			(size 0.519938 1.4986)
			(layers "F.Cu" "F.Mask" "F.Paste")
			(net "GND")
		)
	)
)
